# TIMECARD (Time Appliance Project (Time Card)) — schematic parts with pin connectivity, parts 1–165 of 1119; source: Cadence DE-HDL packaged netlist (pstxprt.dat, pstxnet.dat, pstchip.dat)

C1  CAPACITOR  0.1UF 25V 10%  pkg SMC_0402R_H022  page 16 : 1 = XP3R3V_FPGA ; 2 = SG
C2  CAPACITOR  0.1UF 25V 10%  pkg SMC_0402R_H022  page 27 : 1 = XP12R0V_IN ; 2 = SG
C3  CAPACITOR  0.1UF 25V 10%  pkg SMC_0402R_H022  page 27 : 1 = XP12R0V_A_EN ; 2 = SG
C4  CAPACITOR  0.22UF 6.3V 10%  pkg SMC_0201R  page 27 : 1 = SG ; 2 = XP12R0V_A_TIMER
C5  CAPACITOR  0.1UF 25V 10%  pkg SMC_0402R_H022  page 27 : 1 = XP12R0V_A_SS ; 2 = SG
C6  CAPACITOR  10UF 25V 20%  pkg SMC_0805R_H057  page 27 : 1 = XP12R0V_A_AVIN ; 2 = SG
C7  CAPACITOR  0.1UF 25V 10%  pkg SMC_0402R_H022  page 27 : 1 = XP12R0V_A_IMON ; 2 = SG
C8  CAPACITOR  0.01UF 25V 10%  pkg SMC_0201R  page 27 : 1 = XP12R0V_A_OV ; 2 = SG
C9  CAPACITOR  10UF 25V 20%  pkg SMC_0805R_H057  page 27 : 1 = XP12R0V ; 2 = SG
C10  CAPACITOR  10UF 25V 20%  pkg SMC_0805R_H057  page 27 : 1 = XP12R0V ; 2 = SG
C11  CAPACITOR  100PF 50V 10%  pkg SMC_0201R  page 32 : 1 = UNNAMED_516_CAPACITOR_I29_1 ; 2 = XP5R0V_FB_R_TO_AGND
C12  CAPACITOR  0.1UF 10V 10%  pkg SMC_0402R_H022  page 32 : 1 = XP5R0V ; 2 = SG
C13  CAPACITOR  22UF 10V 20%  pkg SMC_0805R_H057  page 32 : 1 = XP5R0V ; 2 = SG
C14  CAPACITOR  22UF 10V 20%  pkg SMC_0805R_H057  page 32 : 1 = XP5R0V ; 2 = SG
C15  CAPACITOR  22UF 10V 20%  pkg SMC_0805R_H057  page 32 : 1 = XP5R0V ; 2 = SG
C16  CAPACITOR  100PF 50V 10%  pkg SMC_0201R  page 28 : 1 = UNNAMED_517_CAPACITOR_I30_1 ; 2 = XP3R3V_FB_R_TO_AGND
C17  CAPACITOR  0.1UF 10%  pkg SMC_0402R_H022  page 9 : 1 = XP3R3V_FPGA ; 2 = SG
C18  CAPACITOR  0.1UF 10V 10%  pkg SMC_0402R_H022  page 28 : 1 = XP3R3V ; 2 = SG
C19  CAPACITOR  0.1UF 10%  pkg SMC_0402R_H022  page 9 : 1 = C_PCIEREFCLKP ; 2 = PCIE_REFCLKP
C20  CAPACITOR  22UF 10V 20%  pkg SMC_0805R_H057  page 28 : 1 = XP3R3V ; 2 = SG
C21  CAPACITOR  22UF 10V 20%  pkg SMC_0805R_H057  page 28 : 1 = XP3R3V ; 2 = SG
C22  CAPACITOR  22UF 10V 20%  pkg SMC_0805R_H057  page 28 : 1 = XP3R3V ; 2 = SG
C23  CAPACITOR  0.1UF 10%  pkg SMC_0402R_H022  page 9 : 1 = C_PCIEREFCLKN ; 2 = PCIE_REFCLKN
C24  CAPACITOR  0.1UF 10%  pkg SMC_0402R_H022  page 9 : 1 = C_CPU_RX_PCIE_MGT0_TXP ; 2 = CPU_RX_PCIE_MGT0_TXP
C25  CAPACITOR  0.1UF 10%  pkg SMC_0402R_H022  page 9 : 1 = C_CPU_RX_PCIE_MGT0_TXN ; 2 = CPU_RX_PCIE_MGT0_TXN
C26  CAPACITOR  0.1UF 10%  pkg SMC_0402R_H022  page 9 : 1 = C_CPU_RX_PCIE_MGT1_TXP ; 2 = CPU_RX_PCIE_MGT1_TXP
C27  CAPACITOR  0.1UF 10%  pkg SMC_0402R_H022  page 9 : 1 = C_CPU_RX_PCIE_MGT1_TXN ; 2 = CPU_RX_PCIE_MGT1_TXN
C28  CAPACITOR  0.1UF 10%  pkg SMC_0402R_H022  page 9 : 1 = C_CPU_RX_PCIE_MGT2_TXP ; 2 = CPU_RX_PCIE_MGT2_TXP
C29  CAPACITOR  0.1UF 10V 10%  pkg SMC_0402R_H022  page 32 : 1 = R_XP5R0V_EN ; 2 = SG
C30  CAPACITOR  10UF 25V 20%  pkg SMC_0805R_H057  page 32 : 1 = VIN_XP5R0V ; 2 = SG
C31  CAPACITOR  0.022UF 25V 10%  pkg SMC_0402R_H022  page 32 : 1 = XP5R0V_SS ; 2 = XP5R0V_AGND
C32  CAPACITOR  10UF 25V 20%  pkg SMC_0805R_H057  page 32 : 1 = VIN_XP5R0V ; 2 = SG
C33  CAPACITOR  0.1UF 25V 10%  pkg SMC_0402R_H022  page 32 : 1 = VIN_XP5R0V ; 2 = SG
C34  CAPACITOR  0.1UF 10%  pkg SMC_0402R_H022  page 9 : 1 = C_CPU_RX_PCIE_MGT2_TXN ; 2 = CPU_RX_PCIE_MGT2_TXN
C35  CAPACITOR  0.1UF 10%  pkg SMC_0402R_H022  page 9 : 1 = C_CPU_RX_PCIE_MGT3_TXP ; 2 = CPU_RX_PCIE_MGT3_TXP
C36  CAPACITOR  0.1UF 10%  pkg SMC_0402R_H022  page 9 : 1 = C_CPU_RX_PCIE_MGT3_TXN ; 2 = CPU_RX_PCIE_MGT3_TXN
C37  CAPACITOR  0.1UF 10V 10%  pkg SMC_0402R_H022  page 9 : 1 = XP3R3V_FPGA ; 2 = SG
C38  CAPACITOR  0.1UF 10V 10%  pkg SMC_0402R_H022  page 16 : 1 = VDD_PCA9546A ; 2 = SG
C39  CAPACITOR  0.1UF 25V 10%  pkg SMC_0402R_H022  page 17 : 1 = SG ; 2 = XP3R3V_FPGA
C40  CAPACITOR  0.1UF 25V 10%  pkg SMC_0402R_H022  page 18 : 1 = XP3R3V_FPGA ; 2 = SG
C41  CAPACITOR  0.1UF 25V 10%  pkg SMC_0402R_H022  page 32 : 1 = VIN_XP5R0V ; 2 = SG
C42  CAPACITOR  2200PF 50V 10%  pkg SMC_0402R_H022  page 32 : 1 = UNNAMED_516_CAPACITOR_I13_1 ; 2 = XP5R0V_AGND
C43  CAPACITOR  18PF 50V 5%  pkg SMC_0201R  page 32 : 1 = XP5R0V_COMP ; 2 = XP5R0V_AGND
C44  CAPACITOR  0.1UF 25V 10%  pkg SMC_0402R_H022  page 32 : 1 = UNNAMED_516_CAPACITOR_I27_1 ; 2 = XP5R0V_SW
C45  CAPACITOR  1000PF 50V 5%  pkg SMC_0402R_H022  page 32 : 1 = XP5R0V_SW ; 2 = UNNAMED_516_CAPACITOR_I37_2
C46  CAPACITOR  0.1UF 10V 10%  pkg SMC_0402R_H022  page 28 : 1 = XP3R3V_EN ; 2 = SG
C47  CAPACITOR  12PF 50V 5%  pkg SMC_0201R  page 20 : 1 = UNNAMED_9_BNO080LGA28_I29_XOUT3 ; 2 = SG
C48  CAPACITOR  10UF 25V 20%  pkg SMC_0805R_H057  page 28 : 1 = VIN_XP3R3 ; 2 = SG
C49  CAPACITOR  0.022UF 10%  pkg SMC_0402R_H022  page 28 : 1 = XP3R3V_SS ; 2 = XP3R3V_AGND
C50  CAPACITOR  10UF 25V 20%  pkg SMC_0805R_H057  page 28 : 1 = VIN_XP3R3 ; 2 = SG
C51  CAPACITOR  12PF 50V 5%  pkg SMC_0201R  page 20 : 1 = UNNAMED_9_CAPACITOR_I17_1 ; 2 = SG
C52  CAPACITOR  0.1UF 25V 10%  pkg SMC_0402R_H022  page 28 : 1 = VIN_XP3R3 ; 2 = SG
C53  CAPACITOR  0.1UF 25V 10%  pkg SMC_0402R_H022  page 28 : 1 = VIN_XP3R3 ; 2 = SG
C54  CAPACITOR  2200PF 50V 10%  pkg SMC_0402R_H022  page 28 : 1 = UNNAMED_517_CAPACITOR_I17_1 ; 2 = XP3R3V_AGND
C55  CAPACITOR  18PF 25V 5%  pkg SMC_0201R  page 28 : 1 = XP3R3V_COMP ; 2 = XP3R3V_AGND
C56  CAPACITOR  0.1UF 25V 10%  pkg SMC_0402R_H022  page 28 : 1 = UNNAMED_517_CAPACITOR_I27_1 ; 2 = XP3R3V_SW
C57  CAPACITOR  1000PF 50V 5%  pkg SMC_0402R_H022  page 28 : 1 = XP3R3V_SW ; 2 = UNNAMED_517_CAPACITOR_I29_2
C58  CAPACITOR  10UF 25V 20%  pkg SMC_0805R_H057  page 21 : 1 = XP5R0V_MAC ; 2 = SG
C59  CAPACITOR  0.1UF 25V 10%  pkg SMC_0402R_H022  page 21 : 1 = XP5R0V_MAC ; 2 = SG
C60  CAPACITOR  0.1UF 25V 10%  pkg SMC_0402R_H022  page 21 : 1 = XP5R0V_MAC ; 2 = SG
C61  CAPACITOR  10UF 25V 20%  pkg SMC_0805R_H057  page 21 : 1 = XP5R0V_USB_CONN ; 2 = SG
C62  CAPACITOR  0.1UF 25V 10%  pkg SMC_0402R_H022  page 21 : 1 = XP5R0V ; 2 = SG
C63  CAPACITOR  0.1UF 25V 10%  pkg SMC_0402R_H022  page 21 : 1 = XP5R0V_USB_CONN ; 2 = SG
C64  CAPACITOR  10UF 25V 20%  pkg SMC_0805R_H057  page 21 : 1 = XP5R0V_MAC_USB ; 2 = SG
C65  CAPACITOR  0.1UF 25V 10%  pkg SMC_0402R_H022  page 21 : 1 = XP5R0V_MAC_USB ; 2 = SG
C66  CAPACITOR  0.1UF 25V 10%  pkg SMC_0402R_H022  page 21 : 1 = XP5R0V_MAC_USB ; 2 = SG
C67  CAPACITOR  0.1UF 10V 10%  pkg SMC_0402R_H022  page 21 : 1 = XP3R3V_FPGA ; 2 = SG
C68  CAPACITOR  0.1UF 25V 10%  pkg SMC_0402R_H022  page 21 : 1 = XP3R3V_FPGA ; 2 = SG
C69  CAPACITOR  0.1UF 25V 10%  pkg SMC_0402R_H022  page 21 : 1 = USB_PWR_EN ; 2 = SG
C70  CAPACITOR  0.1UF 25V 10%  pkg SMC_0402R_H022  page 21 : 1 = XP5R0V_MAC ; 2 = SG
C71  CAPACITOR  0.1UF 25V 10%  pkg SMC_0402R_H022  page 21 : 1 = XP5R0V_MAC_USB ; 2 = SG
C72  CAPACITOR  10UF 25V 20%  pkg SMC_0805R_H057  page 22 : 1 = XP5R0V_VCC_ANT ; 2 = SG
C73  CAPACITOR  0.1UF 25V 10%  pkg SMC_0402R_H022  page 22 : 1 = XP5R0V_VCC_ANT ; 2 = SG
C74  CAPACITOR  0.1UF 25V 10%  pkg SMC_0402R_H022  page 32 : 1 = XP12R0V ; 2 = SG
C75  CAPACITOR  0.01UF 25V 10%  pkg SMC_0201R  page 32 : 1 = SG ; 2 = XP5R0V_PG
C76  CAPACITOR  0.1UF 25V 10%  pkg SMC_0402R_H022  page 28 : 1 = XP12R0V ; 2 = SG
C77  CAPACITOR  0.01UF 25V 10%  pkg SMC_0201R  page 28 : 1 = SG ; 2 = R_XP3R3V_PG
C78  CAPACITOR  0.1UF 25V 10%  pkg SMC_0402R_H022  page 22 : 1 = XP5R0V_VCC_ANT ; 2 = SG
C79  CAPACITOR  10UF 25V 20%  pkg SMC_0805R_H057  page 22 : 1 = XP3R3V_GPS ; 2 = SG
C80  CAPACITOR  0.1UF 10V 10%  pkg SMC_0402R_H022  page 22 : 1 = XP3R3V_GPS ; 2 = SG
C81  CAPACITOR  0.1UF 10V 10%  pkg SMC_0402R_H022  page 22 : 1 = XP3R3V_FPGA ; 2 = SG
C82  CAPACITOR  0.1UF 10V 10%  pkg SMC_0402R_H022  page 23 : 1 = XP3R3V_FPGA ; 2 = SG
C83  CAPACITOR  0.1UF 10V 10%  pkg SMC_0402R_H022  page 23 : 1 = XP3R3V_FPGA ; 2 = SG
C84  CAPACITOR  0.1UF 10V 10%  pkg SMC_0402R_H022  page 23 : 1 = XP3R3V_FPGA ; 2 = SG
C85  CAPACITOR  0.1UF 10V 10%  pkg SMC_0402R_H022  page 23 : 1 = XP3R3V_FPGA ; 2 = SG
C86  CAPACITOR  18PF 5%  pkg SMC_0201R  page 24 : 1 = SG ; 2 = UNNAMED_524_CAPACITOR_I7_2
C87  CAPACITOR  18PF 5%  pkg SMC_0201R  page 24 : 1 = SG ; 2 = UNNAMED_524_CAPACITOR_I10_2
C88  CAPACITOR  0.1UF 25V 10%  pkg SMC_0402R_H022  page 24 : 1 = XP3R3V_FT4232 ; 2 = SG
C89  CAPACITOR  0.1UF 25V 10%  pkg SMC_0402R_H022  page 24 : 1 = XP3R3V_FPGA ; 2 = SG
C90  CAPACITOR  4.7UF 20%  pkg SMC_0402R_H026  page 24 : 1 = FT4232_VREGOUT ; 2 = SG
C91  CAPACITOR  4.7UF 6.3V 20%  pkg SMC_0402R_H026  page 24 : 1 = XP3R3V_FT4232 ; 2 = SG
C92  CAPACITOR  0.1UF 25V 10%  pkg SMC_0402R_H022  page 24 : 1 = XP3R3V_FPGA ; 2 = SG
C93  CAPACITOR  4.7UF 6.3V 20%  pkg SMC_0402R_H026  page 14 : 1 = XP2R5V_FPGA ; 2 = SG
C94  CAPACITOR  0.1UF 25V 10%  pkg SMC_0402R_H022  page 24 : 1 = XP5R0V_FT4232 ; 2 = SG
C95  CAPACITOR  0.1UF 25V 10%  pkg SMC_0402R_H022  page 24 : 1 = XP3R3V_FT4232 ; 2 = SG
C96  CAPACITOR  0.1UF 25V 10%  pkg SMC_0402R_H022  page 24 : 1 = FT4232_VREGOUT ; 2 = SG
C97  CAPACITOR  0.1UF 25V 10%  pkg SMC_0402R_H022  page 24 : 1 = XP3R3V_FPGA ; 2 = SG
C98  CAPACITOR  4.7UF 6.3V 20%  pkg SMC_0402R_H026  page 24 : 1 = XP3R3V_VPLL ; 2 = SG
C99  CAPACITOR  4.7UF 6.3V 20%  pkg SMC_0402R_H026  page 24 : 1 = XP3R3V_VPHY ; 2 = SG
C100  CAPACITOR  0.1UF 25V 10%  pkg SMC_0402R_H022  page 24 : 1 = XP3R3V_VPLL ; 2 = SG
C101  CAPACITOR  0.1UF 25V 10%  pkg SMC_0402R_H022  page 24 : 1 = XP3R3V_VPHY ; 2 = SG
C102  CAPACITOR  0.1UF 25V 10%  pkg SMC_0402R_H022  page 24 : 1 = XP3R3V_FPGA ; 2 = SG
C103  CAPACITOR  0.1UF 10V 10%  pkg SMC_0402R_H022  page 14 : 1 = XP3R3V_FPGA ; 2 = SG
C104  CAPACITOR  0.1UF 10V 10%  pkg SMC_0402R_H022  page 14 : 1 = FPGA_MGTAVTT ; 2 = SG
C105  CAPACITOR  0.1UF 10V 10%  pkg SMC_0402R_H022  page 14 : 1 = XP1R0V_FPGA_MGTAVCC ; 2 = SG
C106  CAPACITOR  0.1UF 10V 10%  pkg SMC_0402R_H022  page 14 : 1 = XP1R8V_FPGA_VCCAUX ; 2 = SG
C107  CAPACITOR  0.1UF 10V 10%  pkg SMC_0402R_H022  page 14 : 1 = XP3R3V_FPGA ; 2 = SG
C108  CAPACITOR  0.1UF 10V 10%  pkg SMC_0402R_H022  page 14 : 1 = XP2R5V_FPGA ; 2 = SG
C109  CAPACITOR  0.1UF 10V 10%  pkg SMC_0402R_H022  page 14 : 1 = XP1R0V_FPGA_VCCINT ; 2 = SG
C110  CAPACITOR  0.1UF 10V 10%  pkg SMC_0402R_H022  page 14 : 1 = FPGA_MGTAVTT ; 2 = SG
C111  CAPACITOR  0.1UF 10V 10%  pkg SMC_0402R_H022  page 14 : 1 = XP1R0V_FPGA_MGTAVCC ; 2 = SG
C112  CAPACITOR  0.1UF 10V 10%  pkg SMC_0402R_H022  page 14 : 1 = XP3R3V_FPGA ; 2 = SG
C113  CAPACITOR  0.1UF 10V 10%  pkg SMC_0402R_H022  page 14 : 1 = XP1R8V_FPGA_VCCAUX ; 2 = SG
C114  CAPACITOR  0.1UF 10V 10%  pkg SMC_0402R_H022  page 14 : 1 = XP1R0V_FPGA_VCCINT ; 2 = SG
C115  CAPACITOR  0.1UF 10V 10%  pkg SMC_0402R_H022  page 14 : 1 = XP3R3V_FPGA ; 2 = SG
C116  CAPACITOR  0.1UF 10V 10%  pkg SMC_0402R_H022  page 14 : 1 = XP2R5V_FPGA ; 2 = SG
C117  CAPACITOR  4.7UF 6.3V 20%  pkg SMC_0402R_H026  page 14 : 1 = FPGA_MGTAVTT ; 2 = SG
C118  CAPACITOR  0.1UF 10V 10%  pkg SMC_0402R_H022  page 14 : 1 = XP1R0V_FPGA_MGTAVCC ; 2 = SG
C119  CAPACITOR  0.1UF 10V 10%  pkg SMC_0402R_H022  page 14 : 1 = XP3R3V_FPGA ; 2 = SG
C120  CAPACITOR  4.7UF 6.3V 20%  pkg SMC_0402R_H026  page 14 : 1 = XP1R8V_FPGA_VCCAUX ; 2 = SG
C121  CAPACITOR  0.1UF 10V 10%  pkg SMC_0402R_H022  page 14 : 1 = XP1R0V_FPGA_VCCINT ; 2 = SG
C122  CAPACITOR  0.1UF 10V 10%  pkg SMC_0402R_H022  page 14 : 1 = XP2R5V_FPGA ; 2 = SG
C123  CAPACITOR  0.1UF 25V 10%  pkg SMC_0402R_H022  page 24 : 1 = XP3R3V_FPGA ; 2 = SG
C124  CAPACITOR  0.1UF 10V 10%  pkg SMC_0402R_H022  page 14 : 1 = XP1R0V_FPGA_MGTAVCC ; 2 = SG
C125  CAPACITOR  47UF 4V 20%  pkg SMC_0805R_H057  page 14 : 1 = FPGA_MGTAVTT ; 2 = SG
C126  CAPACITOR  0.1UF 10V 10%  pkg SMC_0402R_H022  page 14 : 1 = XP3R3V_FPGA ; 2 = SG
C127  CAPACITOR  0.1UF 10V 10%  pkg SMC_0402R_H022  page 14 : 1 = XP2R5V_FPGA ; 2 = SG
C128  CAPACITOR  4.7UF 6.3V 20%  pkg SMC_0402R_H026  page 14 : 1 = XP1R8V_FPGA_VCCAUX ; 2 = SG
C129  CAPACITOR  0.1UF 10V 10%  pkg SMC_0402R_H022  page 14 : 1 = XP1R0V_FPGA_VCCINT ; 2 = SG
C130  CAPACITOR  0.1UF 10V 10%  pkg SMC_0402R_H022  page 14 : 1 = XP3R3V_FPGA ; 2 = SG
C131  CAPACITOR  4.7UF 6.3V 20%  pkg SMC_0402R_H026  page 14 : 1 = XP1R0V_FPGA_MGTAVCC ; 2 = SG
C132  CAPACITOR  0.1UF 10V 10%  pkg SMC_0402R_H022  page 14 : 1 = XP3R3V_FPGA ; 2 = SG
C133  CAPACITOR  0.1UF 10V 10%  pkg SMC_0402R_H022  page 14 : 1 = XP1R0V_FPGA_VCCINT ; 2 = SG
C134  CAPACITOR  0.1UF 10V 10%  pkg SMC_0402R_H022  page 14 : 1 = XP3R3V_FPGA ; 2 = SG
C135  CAPACITOR  0.1UF 10V 10%  pkg SMC_0402R_H022  page 14 : 1 = XP2R5V_FPGA ; 2 = SG
C136  CAPACITOR  0.1UF 10V 10%  pkg SMC_0402R_H022  page 14 : 1 = XP1R2V_FPGA ; 2 = SG
C137  CAPACITOR  47UF 4V 20%  pkg SMC_0805R_H057  page 14 : 1 = XP1R0V_FPGA_MGTAVCC ; 2 = SG
C138  CAPACITOR  4.7UF 6.3V 20%  pkg SMC_0402R_H026  page 14 : 1 = XP1R8V_FPGA_VCCAUX ; 2 = SG
C139  CAPACITOR  0.1UF 10V 10%  pkg SMC_0402R_H022  page 14 : 1 = XP3R3V_FPGA ; 2 = SG
C140  CAPACITOR  0.1UF 10V 10%  pkg SMC_0402R_H022  page 14 : 1 = XP3R3V_FPGA ; 2 = SG
C141  CAPACITOR  0.1UF 10V 10%  pkg SMC_0402R_H022  page 14 : 1 = XP1R0V_FPGA_VCCINT ; 2 = SG
C142  CAPACITOR  0.1UF 10V 10%  pkg SMC_0402R_H022  page 14 : 1 = XP2R5V_FPGA ; 2 = SG
C143  CAPACITOR  47UF 4V 20%  pkg SMC_0805R_H057  page 14 : 1 = XP1R2V_FPGA ; 2 = SG
C144  CAPACITOR  0.1UF 10V 10%  pkg SMC_0402R_H022  page 14 : 1 = XP3R3V_FPGA ; 2 = SG
C145  CAPACITOR  0.1UF 10V 10%  pkg SMC_0402R_H022  page 14 : 1 = XP3R3V_FPGA ; 2 = SG
C146  CAPACITOR  0.1UF 10V 10%  pkg SMC_0402R_H022  page 14 : 1 = XP2R5V_FPGA ; 2 = SG
C147  CAPACITOR  0.1UF 10V 10%  pkg SMC_0402R_H022  page 14 : 1 = XP1R0V_FPGA_VCCINT ; 2 = SG
C148  CAPACITOR  0.1UF 10V 10%  pkg SMC_0402R_H022  page 14 : 1 = XP1R0V_FPGA ; 2 = SG
C149  CAPACITOR  0.1UF 10V 10%  pkg SMC_0402R_H022  page 14 : 1 = XP3R3V_FPGA ; 2 = SG
C150  CAPACITOR  0.1UF 10V 10%  pkg SMC_0402R_H022  page 14 : 1 = XP1R8V_FPGA ; 2 = SG
C151  CAPACITOR  0.1UF 10V 10%  pkg SMC_0402R_H022  page 14 : 1 = XP2R5V_FPGA ; 2 = SG
C152  CAPACITOR  0.1UF 10V 10%  pkg SMC_0402R_H022  page 14 : 1 = XP1R0V_FPGA_VCCINT ; 2 = SG
C153  CAPACITOR  0.1UF 10V 10%  pkg SMC_0402R_H022  page 14 : 1 = XP3R3V_FPGA ; 2 = SG
C154  CAPACITOR  4.7UF 6.3V 20%  pkg SMC_0402R_H026  page 14 : 1 = XP3R3V_FPGA ; 2 = SG
C155  CAPACITOR  47UF 4V 20%  pkg SMC_0805R_H057  page 14 : 1 = XP1R0V_FPGA ; 2 = SG
C156  CAPACITOR  0.1UF 10V 10%  pkg SMC_0402R_H022  page 14 : 1 = XP1R0V_FPGA_VCCINT ; 2 = SG
C157  CAPACITOR  0.1UF 10V 10%  pkg SMC_0402R_H022  page 14 : 1 = XP3R3V_FPGA ; 2 = SG
C158  CAPACITOR  22UF 10V 20%  pkg SMC_0805R_H057  page 14 : 1 = XP1R8V_FPGA ; 2 = SG
C159  CAPACITOR  4.7UF 6.3V 20%  pkg SMC_0402R_H026  page 14 : 1 = XP3R3V_FPGA ; 2 = SG
C160  CAPACITOR  4.7UF 6.3V 20%  pkg SMC_0402R_H026  page 14 : 1 = XP2R5V_FPGA ; 2 = SG
C161  CAPACITOR  0.1UF 10V 10%  pkg SMC_0402R_H022  page 14 : 1 = XP1R0V_FPGA_VCCINT ; 2 = SG
C162  CAPACITOR  0.1UF 10V 10%  pkg SMC_0402R_H022  page 14 : 1 = XP3R3V_FPGA ; 2 = SG
C163  CAPACITOR  4.7UF 6.3V 20%  pkg SMC_0402R_H026  page 14 : 1 = XP3R3V_FPGA ; 2 = SG
C164  CAPACITOR  22UF 10V 20%  pkg SMC_0805R_H057  page 14 : 1 = XP2R5V_FPGA ; 2 = SG
C165  CAPACITOR  0.1UF 10V 10%  pkg SMC_0402R_H022  page 14 : 1 = XP3R3V_FPGA ; 2 = SG
